FILE_TYPE = CONNECTIVITY;
{Allegro Design Entry HDL 16.6-p007 (v16-6-112F) 10/10/2012}
"PAGE_NUMBER" = 153;
0"NC";
1"GND\g";
2"GND\g";
3"P3V3_STBY\g";
4"P3V3_STBY\g";
5"P3V3_STBY\g";
6"GND\g";
7"P3V3_STBY\g";
8"P3V3_STBY\g";
9"GND\g";
10"GND\g";
11"GND\g";
12"P3V3_STBY\g";
13"PU_SPI0_RST";
14"PU_BIOS_SPI_HOLD0_N";
15"PU_BIOS_SPI_WP0_N";
16"SPI_MISO_R0";
17"SPI_SWITCH_MOSI_R0";
18"TP_SPI_0_3";
19"TP_SPI_0_0";
20"TP_SPI_0_4";
21"PU_BIOS_SPI_WP1_N";
22"TP_SPI_1_5";
23"TP_SPI_1_4";
24"TP_SPI_1_3";
25"TP_SPI_1_2";
26"TP_SPI_1_0";
27"SPI_CS0_SECONDARY_R_N";
28"SPI_SWITCH_MOSI_R1";
29"PU_BIOS_SPI_HOLD1_N";
30"PU_BIOS_SPI_WP1_N";
31"SPI_MISO_R1";
32"SPI_CLK_R1";
33"SPI_SWITCH_MISO";
34"PU_SPI1_RST";
35"SPI_BIOS_SOCKET_IO2";
36"TP_SPI_0_1";
37"TP_SPI_1_6";
38"TP_SPI_1_1";
39"SPI_SWITCH_MOSI";
40"SPI_BIOS_SOCKET_IO2";
41"SPI_CS0_PRIMARY_R_N";
42"SPI_CLK_R0";
43"SPI_SWITCH_CS0_N";
44"SPI_SWITCH_CLK";
45"SPI_SWITCH_MISO";
46"SPI_BIOS_SOCKET_IO3";
47"PU_BIOS_SPI_WP0_N";
48"PU_BIOS_SPI_HOLD0_N";
49"SPI_BIOS_SOCKET_IO3";
50"SPI_SWITCH_CLK";
51"TP_SPI_0_6";
52"TP_SPI_0_5";
53"TP_SPI_0_2";
54"SPI_SWITCH_MOSI";
55"PU_BIOS_SPI_HOLD1_N";
%"RES"
"1","(-6500,3350)","0","mstr_discrete","I108";
;
CDS_SEC"1"
CDS_LOCATION"R7F37"
WATTAGE"1/16W"
PACK_TYPE"0402"
PART_NUMBER"G21796-074"
TOLERANCE"1%"
VALUE"33.2"
LOCATION"R7F37"
MATERIAL"CHIP"
CDS_LIB"mstr_discrete"
BOM_COST"MIO_BIOS_MEM"
ROOM"SB_SPI"
SEC"1"
SEC_TYPE"0402";
"B"
$PN"2"15;
"A"
$PN"1"40;
%"RES"
"1","(-6475,3075)","0","mstr_discrete","I109";
;
CDS_SEC"1"
VALUE"33.2"
TOLERANCE"1%"
MATERIAL"CHIP"
LOCATION"R7F3"
PART_NUMBER"G21796-074"
WATTAGE"1/16W"
PACK_TYPE"0402"
BOM_COST"MIO_BIOS_MEM"
CDS_LOCATION"R7F3"
NO_XNET_CONNECTION"1"
ROOM"SB_SPI"
CDS_LIB"mstr_discrete"
SEC"1"
SEC_TYPE"0402";
"B"
$PN"2"14;
"A"
$PN"1"46;
%"CAP_A"
"1","(-3925,4500)","0","dev_discrete","I130";
;
VOLTAGE"6.3V"
PACK_TYPE"0402V"
LOCATION"C7F2"
VALUE"1.0UF"
TOLERANCE"10%"
PART_NUMBER"D97712-004"
MATERIAL"X6S"
ROOM"SB_SPI"
SEC"1"
SEC_TYPE"0402V"
CDS_SEC"1"
BOM_COST"MIO_BIOS_MEM"
NO_XNET_CONNECTION"1"
CDS_LOCATION"C7F2"
CDS_LIB"dev_discrete";
"B"
$PN"2"1;
"A"
$PN"1"12;
%"CAP_A"
"1","(-3625,4500)","0","dev_discrete","I131";
;
TOLERANCE"10%"
VOLTAGE"25V"
PART_NUMBER"A36096-045"
MATERIAL"X7R"
PACK_TYPE"0402V"
VALUE"0.01UF"
LOCATION"C7F1"
ROOM"SB_SPI"
SEC"1"
SEC_TYPE"0402V"
CDS_SEC"1"
BOM_COST"MIO_BIOS_MEM"
NO_XNET_CONNECTION"1"
CDS_LOCATION"C7F1"
CDS_LIB"dev_discrete";
"B"
$PN"2"1;
"A"
$PN"1"12;
%"GND"
"1","(-3625,4200)","0","mstr_symbols","I133";
;
HDL_POWER"GND"
SIZE"1B"
VOLTAGE"0.0V"
CDS_LIB"mstr_symbols"
BODY_TYPE"PLUMBING";
"A\NAC"1;
%"CAP_A"
"1","(-3625,2400)","0","dev_discrete","I136";
;
MATERIAL"X7R"
TOLERANCE"10%"
VOLTAGE"25V"
VALUE"0.01UF"
LOCATION"C3T5"
PART_NUMBER"A36096-045"
PACK_TYPE"0402V"
GROUP"NI_BIOS_ROM2"
CDS_LIB"dev_discrete"
CDS_LOCATION"C3T5"
ROOM"SB_SPI"
CDS_SEC"1"
BOM_COST"MIO_BIOS_MEM"
NO_XNET_CONNECTION"1"
SEC_TYPE"0402V"
SEC"1";
"B"
$PN"2"2;
"A"
$PN"1"4;
%"CAP_A"
"1","(-3925,2400)","0","dev_discrete","I138";
;
CDS_SEC"1"
TOLERANCE"10%"
MATERIAL"X6S"
VOLTAGE"6.3V"
VALUE"1.0UF"
LOCATION"C3T4"
PACK_TYPE"0402V"
GROUP"NI_BIOS_ROM2"
PART_NUMBER"D97712-004"
SEC_TYPE"0402V"
SEC"1"
CDS_LOCATION"C3T4"
CDS_LIB"dev_discrete"
ROOM"SB_SPI"
BOM_COST"MIO_BIOS_MEM"
NO_XNET_CONNECTION"1";
"B"
$PN"2"2;
"A"
$PN"1"4;
%"GND"
"1","(-3625,2100)","0","mstr_symbols","I139";
;
BODY_TYPE"PLUMBING"
CDS_LIB"mstr_symbols"
VOLTAGE"0.0V"
HDL_POWER"GND"
SIZE"1B";
"A\NAC"2;
%"RES"
"1","(-1450,4425)","0","mstr_discrete","I140";
;
CDS_SEC"1"
TOLERANCE"1%"
VALUE"10.0K"
WATTAGE"1/16W"
PART_NUMBER"G21796-016"
MATERIAL"CHIP"
LOCATION"R7F32"
PACK_TYPE"0402"
CDS_LOCATION"R7F32"
ROOM"SB_SPI"
CDS_LIB"mstr_discrete"
BOM_COST"MIO_BIOS_MEM"
SEC_TYPE"0402"
SEC"1"
NO_XNET_CONNECTION"1";
"B"
$PN"2"48;
"A"
$PN"1"3;
%"P3V3_STBY"
"1","(-1750,4625)","0","mstr_symbols","I141";
;
HDL_POWER"P3V3_STBY"
BODY_TYPE"PLUMBING"
VOLTAGE"3.3V"
CDS_LIB"mstr_symbols"
SIZE"1B";
"G\NAC"3;
%"W25Q256"
"1","(-4700,3975)","0","mstr_memory","I146";
;
CDS_SEC"1"
PART_NUMBER"H25002-001"
MATERIAL"IC"
LOCATION"U7F1"
SEC_TYPE"XSOI"
SEC"1"
ROOM"SB_SPI"
CDS_LOCATION"U7F1"
BOM_COST"MIO_BIOS_MEM"
PACK_TYPE"XSOI"
CDS_LIB"mstr_memory";
"HOLD_N_IO<3>"
$PN"1"14;
"RESET_N"
$PN"3"13;
"DI_IO<0>"
$PN"15"17;
"CS_N"
$PN"7"41;
"VCC"
$PN"2"12;
"CLK"
$PN"16"42;
"DO_IO<1>"
$PN"8"16;
"GND"
$PN"10"11;
"NC<6>"
$PN"4"51;
"NC<5>"
$PN"5"52;
"NC<4>"
$PN"6"20;
"NC<3>"
$PN"11"18;
"NC<2>"
$PN"12"53;
"NC<1>"
$PN"13"36;
"NC<0>"
$PN"14"19;
"WP_N_IO<2>"
$PN"9"15;
%"RES"
"2","(-5875,2325)","2","mstr_discrete","I150";
;
CDS_SEC"1"
VALUE"4.75K"
LOCATION"R3T3"
TOLERANCE"1%"
MATERIAL"EMPTY"
GROUP"NI_BIOS_ROM2"
PACK_TYPE"0402"
PART_NUMBER"G21796-072"
WATTAGE"1/16W"
CDS_LOCATION"R3T3"
ROOM"SB_SPI"
CDS_LIB"mstr_discrete"
NO_XNET_CONNECTION"1"
SEC"1"
BOM_COST"MIO_BIOS_MEM"
SEC_TYPE"0402";
"A"
$PN"1"4;
"B"
$PN"2"34;
%"P3V3_STBY"
"1","(-6375,2725)","0","mstr_symbols","I151";
;
HDL_POWER"P3V3_STBY"
BODY_TYPE"PLUMBING"
CDS_LIB"mstr_symbols"
SIZE"1B"
VOLTAGE"3.3V";
"G\NAC"4;
%"RES"
"2","(-6175,2325)","2","mstr_discrete","I152";
;
CDS_SEC"1"
WATTAGE"1/16W"
PART_NUMBER"G21796-072"
TOLERANCE"1%"
MATERIAL"CHIP"
VALUE"4.75K"
LOCATION"R3T5"
PACK_TYPE"0402"
GROUP"NI_BIOS_ROM2"
CDS_LIB"mstr_discrete"
ROOM"SB_SPI"
CDS_LOCATION"R3T5"
NO_XNET_CONNECTION"1"
SEC"1"
BOM_COST"MIO_BIOS_MEM"
SEC_TYPE"0402";
"A"
$PN"1"4;
"B"
$PN"2"27;
%"RES"
"1","(-6275,1675)","0","mstr_discrete","I155";
;
CDS_SEC"1"
TOLERANCE"1%"
LOCATION"R3T2"
WATTAGE"1/16W"
GROUP"NI_BIOS_ROM2"
MATERIAL"CHIP"
VALUE"33.2"
PART_NUMBER"G21796-074"
PACK_TYPE"0402"
BOM_COST"MIO_BIOS_MEM"
ROOM"SB_SPI"
CDS_LOCATION"R3T2"
SEC"1"
SEC_TYPE"0402"
CDS_LIB"mstr_discrete";
"B"
$PN"2"31;
"A"
$PN"1"33;
%"RES"
"1","(-6425,1425)","0","mstr_discrete","I156";
;
CDS_SEC"1"
LOCATION"R3U1"
VALUE"33.2"
WATTAGE"1/16W"
TOLERANCE"1%"
PACK_TYPE"0402"
PART_NUMBER"G21796-074"
MATERIAL"CHIP"
GROUP"NI_BIOS_ROM2"
SEC"1"
SEC_TYPE"0402"
NO_XNET_CONNECTION"1"
BOM_COST"MIO_BIOS_MEM"
ROOM"SB_SPI"
CDS_LOCATION"R3U1"
CDS_LIB"mstr_discrete";
"B"
$PN"2"30;
"A"
$PN"1"35;
%"RES"
"1","(-6425,1200)","0","mstr_discrete","I157";
;
CDS_SEC"1"
LOCATION"R3T1"
WATTAGE"1/16W"
VALUE"33.2"
PACK_TYPE"0402"
PART_NUMBER"G21796-074"
MATERIAL"CHIP"
GROUP"NI_BIOS_ROM2"
TOLERANCE"1%"
CDS_LIB"mstr_discrete"
ROOM"SB_SPI"
BOM_COST"MIO_BIOS_MEM"
NO_XNET_CONNECTION"1"
CDS_LOCATION"R3T1"
SEC"1"
SEC_TYPE"0402";
"B"
$PN"2"29;
"A"
$PN"1"49;
%"RES"
"1","(-6550,3825)","0","mstr_discrete","I166";
;
MATERIAL"CHIP"
WATTAGE"1/16W"
LOCATION"R8F8"
TOLERANCE"1%"
VALUE"33.2"
PACK_TYPE"0402"
PART_NUMBER"G21796-074"
CDS_LIB"mstr_discrete"
ROOM"MIO_BIOS_MEM"
CDS_LOCATION"R8F8"
$SEC"1"
CDS_SEC"1";
"B"
$PN"2"42;
"A"
$PN"1"44;
%"RES"
"1","(-6275,1825)","0","mstr_discrete","I167";
;
CDS_SEC"1"
TOLERANCE"1%"
VALUE"33.2"
WATTAGE"1/16W"
LOCATION"R8F7"
PACK_TYPE"0402"
PART_NUMBER"G21796-074"
MATERIAL"CHIP"
GROUP"NI_BIOS_ROM2"
SEC_TYPE"0402"
SEC"1"
CDS_LOCATION"R8F7"
CDS_LIB"mstr_discrete"
ROOM"MIO_BIOS_MEM";
"B"
$PN"2"32;
"A"
$PN"1"50;
%"RES"
"2","(-1750,3925)","0","mstr_discrete","I168";
;
CDS_SEC"1"
VALUE"10.0K"
PACK_TYPE"0402"
WATTAGE"1/16W"
LOCATION"R7F28"
TOLERANCE"1%"
MATERIAL"CHIP"
PART_NUMBER"G21796-016"
CDS_LIB"mstr_discrete"
CDS_LOCATION"R7F28"
BOM_COST"MIO_BIOS_MEM"
SEC_TYPE"0402"
ROOM"SB_SPI"
NO_XNET_CONNECTION"1"
SEC"1";
"A"
$PN"1"5;
"B"
$PN"2"47;
%"P3V3_STBY"
"1","(-1750,4175)","0","mstr_symbols","I169";
;
HDL_POWER"P3V3_STBY"
BODY_TYPE"PLUMBING"
VOLTAGE"3.3V"
SIZE"1B"
CDS_LIB"mstr_symbols";
"G\NAC"5;
%"RES"
"2","(-1750,3550)","0","mstr_discrete","I170";
;
CDS_SEC"1"
PART_NUMBER"G21796-016"
PACK_TYPE"0402"
WATTAGE"1/16W"
MATERIAL"EMPTY"
TOLERANCE"1%"
VALUE"10.0K"
LOCATION"R7F30"
CDS_LIB"mstr_discrete"
CDS_LOCATION"R7F30"
ROOM"SB_SPI"
SEC"1"
SEC_TYPE"0402"
BOM_COST"MIO_BIOS_MEM";
"A"
$PN"1"47;
"B"
$PN"2"6;
%"GND"
"1","(-1750,3325)","0","mstr_symbols","I172";
;
BODY_TYPE"PLUMBING"
VOLTAGE"0.0V"
SIZE"1B"
CDS_LIB"mstr_symbols"
HDL_POWER"GND";
"A\NAC"6;
%"RES"
"1","(-1450,2325)","0","mstr_discrete","I174";
;
CDS_SEC"1"
TOLERANCE"1%"
MATERIAL"CHIP"
VALUE"10.0K"
PACK_TYPE"0402"
LOCATION"R3T4"
PART_NUMBER"G21796-016"
WATTAGE"1/16W"
GROUP"NI_BIOS_ROM2"
ROOM"SB_SPI"
CDS_LOCATION"R3T4"
CDS_LIB"mstr_discrete"
BOM_COST"MIO_BIOS_MEM"
SEC_TYPE"0402"
SEC"1";
"B"
$PN"2"55;
"A"
$PN"1"7;
%"P3V3_STBY"
"1","(-1750,2525)","0","mstr_symbols","I175";
;
HDL_POWER"P3V3_STBY"
BODY_TYPE"PLUMBING"
VOLTAGE"3.3V"
CDS_LIB"mstr_symbols"
SIZE"1B";
"G\NAC"7;
%"P3V3_STBY"
"1","(-1750,2075)","0","mstr_symbols","I176";
;
HDL_POWER"P3V3_STBY"
BODY_TYPE"PLUMBING"
VOLTAGE"3.3V"
SIZE"1B"
CDS_LIB"mstr_symbols";
"G\NAC"8;
%"RES"
"2","(-1750,1825)","0","mstr_discrete","I178";
;
CDS_SEC"1"
PART_NUMBER"G21796-016"
PACK_TYPE"0402"
LOCATION"R3T12"
GROUP"NI_BIOS_ROM2"
TOLERANCE"1%"
MATERIAL"CHIP"
VALUE"10.0K"
WATTAGE"1/16W"
CDS_LIB"mstr_discrete"
CDS_LOCATION"R3T12"
SEC_TYPE"0402"
BOM_COST"MIO_BIOS_MEM"
SEC"1"
ROOM"SB_SPI";
"A"
$PN"1"8;
"B"
$PN"2"21;
%"RES"
"2","(-1750,1450)","0","mstr_discrete","I179";
;
CDS_SEC"1"
TOLERANCE"1%"
VALUE"10.0K"
WATTAGE"1/16W"
PACK_TYPE"0402"
MATERIAL"EMPTY"
GROUP"NI_BIOS_ROM2"
PART_NUMBER"G21796-016"
LOCATION"R3T9"
CDS_LIB"mstr_discrete"
CDS_LOCATION"R3T9"
ROOM"SB_SPI"
SEC"1"
SEC_TYPE"0402"
BOM_COST"MIO_BIOS_MEM";
"A"
$PN"1"21;
"B"
$PN"2"9;
%"GND"
"1","(-1750,1225)","0","mstr_symbols","I180";
;
BODY_TYPE"PLUMBING"
VOLTAGE"0.0V"
SIZE"1B"
CDS_LIB"mstr_symbols"
HDL_POWER"GND";
"A\NAC"9;
%"RES"
"1","(-6525,3925)","0","mstr_discrete","I181";
;
CDS_SEC"1"
PART_NUMBER"G21796-074"
PACK_TYPE"0402"
WATTAGE"1/16W"
VALUE"33.2"
MATERIAL"CHIP"
TOLERANCE"1%"
LOCATION"R7F29"
CDS_LOCATION"R7F29"
CDS_LIB"mstr_discrete"
ROOM"SB_SPI"
BOM_COST"MIO_BIOS_MEM"
SEC"1"
SEC_TYPE"0402";
"B"
$PN"2"17;
"A"
$PN"1"39;
%"RES"
"1","(-6275,1725)","0","mstr_discrete","I184";
;
CDS_SEC"1"
PACK_TYPE"0402"
TOLERANCE"1%"
LOCATION"R3T10"
WATTAGE"1/16W"
VALUE"33.2"
MATERIAL"CHIP"
PART_NUMBER"G21796-074"
GROUP"NI_BIOS_ROM2"
CDS_LIB"mstr_discrete"
CDS_LOCATION"R3T10"
ROOM"SB_SPI"
BOM_COST"MIO_BIOS_MEM"
SEC_TYPE"0402"
SEC"1";
"B"
$PN"2"28;
"A"
$PN"1"54;
%"W25Q256FVFIG-GP"
"1","(-4950,1800)","0","w_hdl","I185";
;
CDS_SEC"1"
CDS_LOCATION"U3T1"
LOCATION"U3T1"
VALUE"W25Q256FVFIG-GP"
GROUP"NI_BIOS_ROM2"
PACK_TYPE"MEMORY-G4"
SEC"1"
SEC_TYPE"MEMORY-G4"
PART_NUMBER"72.25256.H01"
CDS_LIB"w_hdl"
CDS_LMAN_SYM_OUTLINE"-275,375,275,-375";
"CLK"
$PN"16"32;
"DI/IO0"
$PN"15"28;
"NC#14"
$PN"14"26;
"NC#13"
$PN"13"38;
"NC#12"
$PN"12"25;
"NC#11"
$PN"11"24;
"GND"
$PN"10"10;
"WP#/IO2 \B"
$PN"9"30;
"DO/IO1"
$PN"8"31;
"CS# \B"
$PN"7"27;
"NC#6"
$PN"6"23;
"NC#5"
$PN"5"22;
"NC#4"
$PN"4"37;
"RESET# \B"
$PN"3"34;
"VCC"
$PN"2"4;
"HOLD#/IO3 \B"
$PN"1"29;
%"GND"
"1","(-4325,1400)","0","mstr_symbols","I186";
;
HDL_POWER"GND"
CDS_LIB"mstr_symbols"
VOLTAGE"0"
SIZE"1B"
BODY_TYPE"PLUMBING";
"A\NAC"10;
%"RES"
"1","(-6550,3625)","0","mstr_discrete","I187";
;
MATERIAL"CHIP"
PACK_TYPE"0402"
PART_NUMBER"G21497-005"
TOLERANCE"5%"
LOCATION"R7W5"
VALUE"0.0"
WATTAGE"1/16W"
CDS_LOCATION"R7W5"
ROOM"MIO_BIOS_MEM"
$SEC"1"
CDS_SEC"1"
CDS_LIB"mstr_discrete";
"B"
$PN"2"41;
"A"
$PN"1"43;
%"RES"
"2","(-5950,4425)","2","mstr_discrete","I90";
;
CDS_SEC"1"
MATERIAL"EMPTY"
TOLERANCE"1%"
WATTAGE"1/16W"
LOCATION"R7F6"
VALUE"4.75K"
PART_NUMBER"G21796-072"
PACK_TYPE"0402"
CDS_LIB"mstr_discrete"
CDS_LOCATION"R7F6"
ROOM"SB_SPI"
NO_XNET_CONNECTION"1"
SEC"1"
SEC_TYPE"0402"
BOM_COST"MIO_BIOS_MEM";
"A"
$PN"1"12;
"B"
$PN"2"13;
%"GND"
"1","(-4000,3600)","0","mstr_symbols","I91";
;
BODY_TYPE"PLUMBING"
VOLTAGE"0"
HDL_POWER"GND"
CDS_LIB"mstr_symbols"
SIZE"1B";
"A\NAC"11;
%"RES"
"2","(-6250,4425)","2","mstr_discrete","I94";
;
CDS_SEC"1"
TOLERANCE"1%"
PART_NUMBER"G21796-072"
LOCATION"R7F5"
WATTAGE"1/16W"
VALUE"4.75K"
PACK_TYPE"0402"
MATERIAL"CHIP"
CDS_LOCATION"R7F5"
CDS_LIB"mstr_discrete"
ROOM"SB_SPI"
SEC_TYPE"0402"
BOM_COST"MIO_BIOS_MEM"
SEC"1"
NO_XNET_CONNECTION"1";
"A"
$PN"1"12;
"B"
$PN"2"41;
%"P3V3_STBY"
"1","(-6450,4825)","0","mstr_symbols","I95";
;
HDL_POWER"P3V3_STBY"
VOLTAGE"3.3V"
CDS_LIB"mstr_symbols"
SIZE"1B"
BODY_TYPE"PLUMBING";
"G\NAC"12;
%"RES"
"1","(-6275,3975)","0","mstr_discrete","I98";
;
CDS_SEC"1"
PART_NUMBER"G21796-074"
LOCATION"R7F4"
MATERIAL"CHIP"
WATTAGE"1/16W"
VALUE"33.2"
PACK_TYPE"0402"
TOLERANCE"1%"
CDS_LIB"mstr_discrete"
CDS_LOCATION"R7F4"
ROOM"SB_SPI"
BOM_COST"MIO_BIOS_MEM"
SEC"1"
SEC_TYPE"0402";
"B"
$PN"2"16;
"A"
$PN"1"45;
END.
